# T6G (Grand Teton) — schematic netlist excerpt (pin names and nets, part order shuffled) for the footprints in the layout excerpt that follows; sources: Cadence DE-HDL packaged netlist, KiCad conversion of 04192023_DAF0TMB3IC0_F0TG_MB_C_brd_V02_OCP.brd

C485  Q_CAP  1UF 4V 20% X6S  pkg 0201  page 356 : A = P0V9_CPU1_RT3_2A ; B = GND
R90  Q_RES  1K 1% EMPTY  pkg 0402LF  page 87 : A = P3V3 ; B = PWRGD_CHB_CPU0_DIMM
R8176  Q_RES  0 5% CHIP  pkg 0402LF  page 210 : A = SMB_VR_3V3STBY_SDA ; B = PVDDCR_CPU0_P1_PMSDA_R

(kicad_pcb
	(version 20260206)
	(generator "pcbnew")
	(generator_version "10.0")
	(general
		(thickness 1.6)
		(legacy_teardrops no)
	)
	(paper "A4")
	(title_block
		(title "04192023_DAF0TMB3IC0_F0TG_MB_C_brd_V02_OCP.brd")
		(comment 1 "Grand Teton / footprints 6282-6284 of 8354")
	)
	(layers
		(0 "F.Cu" signal "TOP")
		(4 "In1.Cu" signal "GND")
		(6 "In2.Cu" signal "IN1")
		(8 "In3.Cu" signal "GND1")
		(10 "In4.Cu" signal "IN2")
		(12 "In5.Cu" signal "GND2")
		(14 "In6.Cu" signal "IN3")
		(16 "In7.Cu" signal "GND3")
		(18 "In8.Cu" signal "VCC")
		(20 "In9.Cu" signal "VCC1")
		(22 "In10.Cu" signal "GND4")
		(24 "In11.Cu" signal "IN4")
		(26 "In12.Cu" signal "GND5")
		(28 "In13.Cu" signal "IN5")
		(30 "In14.Cu" signal "GND6")
		(32 "In15.Cu" signal "IN6")
		(34 "In16.Cu" signal "GND7")
		(2 "B.Cu" signal "BOTTOM")
		(9 "F.Adhes" user "F.Adhesive")
		(11 "B.Adhes" user "B.Adhesive")
		(13 "F.Paste" user "Package Geometry/Pastemask Top")
		(15 "B.Paste" user "Package Geometry/Pastemask Bottom")
		(5 "F.SilkS" user "Ref Des/Silkscreen Top")
		(7 "B.SilkS" user "Ref Des/Silkscreen Bottom")
		(1 "F.Mask" user "Board Geometry/Soldermask Top")
		(3 "B.Mask" user "Board Geometry/Soldermask Bottom")
		(17 "Dwgs.User" user "User.Drawings")
		(19 "Cmts.User" user "User.Comments")
		(21 "Eco1.User" user "User.Eco1")
		(23 "Eco2.User" user "User.Eco2")
		(25 "Edge.Cuts" user "Board Geometry/Outline")
		(27 "Margin" user)
		(31 "F.CrtYd" user "Package Geometry/Place Bound Top")
		(29 "B.CrtYd" user "Package Geometry/Place Bound Bottom")
		(35 "F.Fab" user "Ref Des/Assembly Top")
		(33 "B.Fab" user "Ref Des/Assembly Bottom")
	)
	(footprint ""
		(layer "B.Cu")
		(at 296.479722 -193.99631)
		(property "Reference" "R90"
			(at 0 0 0)
			(layer "B.SilkS")
			(hide yes)
			(effects
				(font
					(size 1.27 1.27)
				)
				(justify mirror)
			)
		)
		(property "Value" ""
			(at 0 0 0)
			(layer "B.Fab")
			(effects
				(font
					(size 1.27 1.27)
				)
				(justify mirror)
			)
		)
		(duplicate_pad_numbers_are_jumpers no)
		(fp_line
			(start -0.7874 -0.4064)
			(end -0.7874 0.4064)
			(stroke
				(width 0.1524)
				(type default)
			)
			(layer "B.SilkS")
		)
		(fp_line
			(start -0.7874 0.4064)
			(end 0.7874 0.4064)
			(stroke
				(width 0.1524)
				(type default)
			)
			(layer "B.SilkS")
		)
		(fp_line
			(start 0.7874 -0.4064)
			(end -0.7874 -0.4064)
			(stroke
				(width 0.1524)
				(type default)
			)
			(layer "B.SilkS")
		)
		(fp_line
			(start 0.7874 0.4064)
			(end 0.7874 -0.4064)
			(stroke
				(width 0.1524)
				(type default)
			)
			(layer "B.SilkS")
		)
		(fp_line
			(start -0.67945 -0.3048)
			(end -0.67945 0.3048)
			(stroke
				(width 0.1)
				(type default)
			)
			(layer "B.Fab")
		)
		(fp_line
			(start -0.67945 0.3048)
			(end -0.120396 0.3048)
			(stroke
				(width 0.1)
				(type default)
			)
			(layer "B.Fab")
		)
		(fp_line
			(start -0.12065 -0.3048)
			(end -0.67945 -0.3048)
			(stroke
				(width 0.1)
				(type default)
			)
			(layer "B.Fab")
		)
		(fp_line
			(start -0.12065 -0.2794)
			(end -0.12065 -0.3048)
			(stroke
				(width 0.1)
				(type default)
			)
			(layer "B.Fab")
		)
		(fp_line
			(start -0.120396 0.2794)
			(end 0.12065 0.2794)
			(stroke
				(width 0.1)
				(type default)
			)
			(layer "B.Fab")
		)
		(fp_line
			(start -0.120396 0.3048)
			(end -0.120396 0.2794)
			(stroke
				(width 0.1)
				(type default)
			)
			(layer "B.Fab")
		)
		(fp_line
			(start 0.12065 -0.305054)
			(end 0.12065 -0.2794)
			(stroke
				(width 0.1)
				(type default)
			)
			(layer "B.Fab")
		)
		(fp_line
			(start 0.12065 -0.2794)
			(end -0.12065 -0.2794)
			(stroke
				(width 0.1)
				(type default)
			)
			(layer "B.Fab")
		)
		(fp_line
			(start 0.12065 0.2794)
			(end 0.12065 0.3048)
			(stroke
				(width 0.1)
				(type default)
			)
			(layer "B.Fab")
		)
		(fp_line
			(start 0.12065 0.3048)
			(end 0.67945 0.3048)
			(stroke
				(width 0.1)
				(type default)
			)
			(layer "B.Fab")
		)
		(fp_line
			(start 0.67945 -0.305054)
			(end 0.12065 -0.305054)
			(stroke
				(width 0.1)
				(type default)
			)
			(layer "B.Fab")
		)
		(fp_line
			(start 0.67945 0.3048)
			(end 0.67945 -0.305054)
			(stroke
				(width 0.1)
				(type default)
			)
			(layer "B.Fab")
		)
		(pad "1" smd circle
			(at 0.40005 0 180)
			(size 0 0)
			(layers "B.Cu" "B.Mask" "B.Paste")
			(net "P3V3")
		)
		(pad "2" smd circle
			(at -0.40005 0 180)
			(size 0 0)
			(layers "B.Cu" "B.Mask" "B.Paste")
			(net "PWRGD_CHB_CPU0_DIMM")
		)
	)
	(footprint ""
		(layer "B.Cu")
		(at 133.683756 -386.766562 90)
		(property "Reference" "C485"
			(at 0 0 90)
			(layer "B.SilkS")
			(hide yes)
			(effects
				(font
					(size 1.27 1.27)
				)
				(justify mirror)
			)
		)
		(property "Value" ""
			(at 0 0 90)
			(layer "B.Fab")
			(effects
				(font
					(size 1.27 1.27)
				)
				(justify mirror)
			)
		)
		(duplicate_pad_numbers_are_jumpers no)
		(fp_line
			(start 0.299974 -0.150114)
			(end -0.299974 -0.150114)
			(stroke
				(width 0.1)
				(type default)
			)
			(layer "B.Fab")
		)
		(fp_line
			(start -0.299974 -0.150114)
			(end -0.299974 0.150114)
			(stroke
				(width 0.1)
				(type default)
			)
			(layer "B.Fab")
		)
		(fp_line
			(start 0.299974 0.150114)
			(end 0.299974 -0.150114)
			(stroke
				(width 0.1)
				(type default)
			)
			(layer "B.Fab")
		)
		(fp_line
			(start -0.299974 0.150114)
			(end 0.299974 0.150114)
			(stroke
				(width 0.1)
				(type default)
			)
			(layer "B.Fab")
		)
		(pad "1" smd rect
			(at 0.2667 0 270)
			(size 0.3048 0.381)
			(layers "B.Cu" "B.Mask" "B.Paste")
			(net "P0V9_CPU1_RT3_2A")
		)
		(pad "2" smd rect
			(at -0.2667 0 270)
			(size 0.3048 0.381)
			(layers "B.Cu" "B.Mask" "B.Paste")
			(net "GND")
		)
	)
	(footprint ""
		(layer "B.Cu")
		(at 91.987878 -140.18641 -90)
		(property "Reference" "R8176"
			(at 0 0 90)
			(layer "B.SilkS")
			(hide yes)
			(effects
				(font
					(size 1.27 1.27)
				)
				(justify mirror)
			)
		)
		(property "Value" ""
			(at 0 0 90)
			(layer "B.Fab")
			(effects
				(font
					(size 1.27 1.27)
				)
				(justify mirror)
			)
		)
		(duplicate_pad_numbers_are_jumpers no)
		(fp_line
			(start -0.7874 0.4064)
			(end 0.7874 0.4064)
			(stroke
				(width 0.1524)
				(type default)
			)
			(layer "B.SilkS")
		)
		(fp_line
			(start 0.7874 0.4064)
			(end 0.7874 -0.4064)
			(stroke
				(width 0.1524)
				(type default)
			)
			(layer "B.SilkS")
		)
		(fp_line
			(start -0.7874 -0.4064)
			(end -0.7874 0.4064)
			(stroke
				(width 0.1524)
				(type default)
			)
			(layer "B.SilkS")
		)
		(fp_line
			(start 0.7874 -0.4064)
			(end -0.7874 -0.4064)
			(stroke
				(width 0.1524)
				(type default)
			)
			(layer "B.SilkS")
		)
		(fp_line
			(start -0.67945 0.3048)
			(end -0.120396 0.3048)
			(stroke
				(width 0.1)
				(type default)
			)
			(layer "B.Fab")
		)
		(fp_line
			(start -0.120396 0.3048)
			(end -0.120396 0.2794)
			(stroke
				(width 0.1)
				(type default)
			)
			(layer "B.Fab")
		)
		(fp_line
			(start 0.12065 0.3048)
			(end 0.67945 0.3048)
			(stroke
				(width 0.1)
				(type default)
			)
			(layer "B.Fab")
		)
		(fp_line
			(start 0.67945 0.3048)
			(end 0.67945 -0.305054)
			(stroke
				(width 0.1)
				(type default)
			)
			(layer "B.Fab")
		)
		(fp_line
			(start -0.120396 0.2794)
			(end 0.12065 0.2794)
			(stroke
				(width 0.1)
				(type default)
			)
			(layer "B.Fab")
		)
		(fp_line
			(start 0.12065 0.2794)
			(end 0.12065 0.3048)
			(stroke
				(width 0.1)
				(type default)
			)
			(layer "B.Fab")
		)
		(fp_line
			(start -0.12065 -0.2794)
			(end -0.12065 -0.3048)
			(stroke
				(width 0.1)
				(type default)
			)
			(layer "B.Fab")
		)
		(fp_line
			(start 0.12065 -0.2794)
			(end -0.12065 -0.2794)
			(stroke
				(width 0.1)
				(type default)
			)
			(layer "B.Fab")
		)
		(fp_line
			(start -0.67945 -0.3048)
			(end -0.67945 0.3048)
			(stroke
				(width 0.1)
				(type default)
			)
			(layer "B.Fab")
		)
		(fp_line
			(start -0.12065 -0.3048)
			(end -0.67945 -0.3048)
			(stroke
				(width 0.1)
				(type default)
			)
			(layer "B.Fab")
		)
		(fp_line
			(start 0.12065 -0.305054)
			(end 0.12065 -0.2794)
			(stroke
				(width 0.1)
				(type default)
			)
			(layer "B.Fab")
		)
		(fp_line
			(start 0.67945 -0.305054)
			(end 0.12065 -0.305054)
			(stroke
				(width 0.1)
				(type default)
			)
			(layer "B.Fab")
		)
		(pad "1" smd circle
			(at 0.40005 0 90)
			(size 0 0)
			(layers "B.Cu" "B.Mask" "B.Paste")
			(net "SMB_VR_3V3STBY_SDA")
		)
		(pad "2" smd circle
			(at -0.40005 0 90)
			(size 0 0)
			(layers "B.Cu" "B.Mask" "B.Paste")
			(net "PVDDCR_CPU0_P1_PMSDA_R")
		)
	)
)
